(kicad_pcb
	(version 20260206)
	(generator "pcbnew")
	(generator_version "10.0")
	(general
		(thickness 1.6)
		(legacy_teardrops no)
	)
	(paper "A4")
	(title_block
		(title "04192023_DAF0TMB3IC0_F0TG_MB_C_brd_V02_OCP.brd")
		(comment 1 "Grand Teton / footprints 8112-8118 of 8354")
	)
	(layers
		(0 "F.Cu" signal "TOP")
		(4 "In1.Cu" signal "GND")
		(6 "In2.Cu" signal "IN1")
		(8 "In3.Cu" signal "GND1")
		(10 "In4.Cu" signal "IN2")
		(12 "In5.Cu" signal "GND2")
		(14 "In6.Cu" signal "IN3")
		(16 "In7.Cu" signal "GND3")
		(18 "In8.Cu" signal "VCC")
		(20 "In9.Cu" signal "VCC1")
		(22 "In10.Cu" signal "GND4")
		(24 "In11.Cu" signal "IN4")
		(26 "In12.Cu" signal "GND5")
		(28 "In13.Cu" signal "IN5")
		(30 "In14.Cu" signal "GND6")
		(32 "In15.Cu" signal "IN6")
		(34 "In16.Cu" signal "GND7")
		(2 "B.Cu" signal "BOTTOM")
		(9 "F.Adhes" user "F.Adhesive")
		(11 "B.Adhes" user "B.Adhesive")
		(13 "F.Paste" user "Package Geometry/Pastemask Top")
		(15 "B.Paste" user "Package Geometry/Pastemask Bottom")
		(5 "F.SilkS" user "Ref Des/Silkscreen Top")
		(7 "B.SilkS" user "Ref Des/Silkscreen Bottom")
		(1 "F.Mask" user "Board Geometry/Soldermask Top")
		(3 "B.Mask" user "Board Geometry/Soldermask Bottom")
		(17 "Dwgs.User" user "User.Drawings")
		(19 "Cmts.User" user "User.Comments")
		(21 "Eco1.User" user "User.Eco1")
		(23 "Eco2.User" user "User.Eco2")
		(25 "Edge.Cuts" user "Board Geometry/Outline")
		(27 "Margin" user)
		(31 "F.CrtYd" user "Package Geometry/Place Bound Top")
		(29 "B.CrtYd" user "Package Geometry/Place Bound Bottom")
		(35 "F.Fab" user "Ref Des/Assembly Top")
		(33 "B.Fab" user "Ref Des/Assembly Bottom")
	)
	(footprint ""
		(layer "B.Cu")
		(at 89.614502 -205.14945 90)
		(property "Reference" "R540"
			(at 0 0 90)
			(layer "B.SilkS")
			(hide yes)
			(effects
				(font
					(size 1.27 1.27)
				)
				(justify mirror)
			)
		)
		(property "Value" ""
			(at 0 0 90)
			(layer "B.Fab")
			(effects
				(font
					(size 1.27 1.27)
				)
				(justify mirror)
			)
		)
		(duplicate_pad_numbers_are_jumpers no)
		(fp_line
			(start 0.7874 -0.4064)
			(end -0.7874 -0.4064)
			(stroke
				(width 0.1524)
				(type default)
			)
			(layer "B.SilkS")
		)
		(fp_line
			(start -0.7874 -0.4064)
			(end -0.7874 0.4064)
			(stroke
				(width 0.1524)
				(type default)
			)
			(layer "B.SilkS")
		)
		(fp_line
			(start 0.7874 0.4064)
			(end 0.7874 -0.4064)
			(stroke
				(width 0.1524)
				(type default)
			)
			(layer "B.SilkS")
		)
		(fp_line
			(start -0.7874 0.4064)
			(end 0.7874 0.4064)
			(stroke
				(width 0.1524)
				(type default)
			)
			(layer "B.SilkS")
		)
		(fp_line
			(start 0.67945 -0.305054)
			(end 0.12065 -0.305054)
			(stroke
				(width 0.1)
				(type default)
			)
			(layer "B.Fab")
		)
		(fp_line
			(start 0.12065 -0.305054)
			(end 0.12065 -0.2794)
			(stroke
				(width 0.1)
				(type default)
			)
			(layer "B.Fab")
		)
		(fp_line
			(start -0.12065 -0.3048)
			(end -0.67945 -0.3048)
			(stroke
				(width 0.1)
				(type default)
			)
			(layer "B.Fab")
		)
		(fp_line
			(start -0.67945 -0.3048)
			(end -0.67945 0.3048)
			(stroke
				(width 0.1)
				(type default)
			)
			(layer "B.Fab")
		)
		(fp_line
			(start 0.12065 -0.2794)
			(end -0.12065 -0.2794)
			(stroke
				(width 0.1)
				(type default)
			)
			(layer "B.Fab")
		)
		(fp_line
			(start -0.12065 -0.2794)
			(end -0.12065 -0.3048)
			(stroke
				(width 0.1)
				(type default)
			)
			(layer "B.Fab")
		)
		(fp_line
			(start 0.12065 0.2794)
			(end 0.12065 0.3048)
			(stroke
				(width 0.1)
				(type default)
			)
			(layer "B.Fab")
		)
		(fp_line
			(start -0.120396 0.2794)
			(end 0.12065 0.2794)
			(stroke
				(width 0.1)
				(type default)
			)
			(layer "B.Fab")
		)
		(fp_line
			(start 0.67945 0.3048)
			(end 0.67945 -0.305054)
			(stroke
				(width 0.1)
				(type default)
			)
			(layer "B.Fab")
		)
		(fp_line
			(start 0.12065 0.3048)
			(end 0.67945 0.3048)
			(stroke
				(width 0.1)
				(type default)
			)
			(layer "B.Fab")
		)
		(fp_line
			(start -0.120396 0.3048)
			(end -0.120396 0.2794)
			(stroke
				(width 0.1)
				(type default)
			)
			(layer "B.Fab")
		)
		(fp_line
			(start -0.67945 0.3048)
			(end -0.120396 0.3048)
			(stroke
				(width 0.1)
				(type default)
			)
			(layer "B.Fab")
		)
		(pad "1" smd circle
			(at 0.40005 0 270)
			(size 0 0)
			(layers "B.Cu" "B.Mask" "B.Paste")
			(net "CPU1_XTRIG_L7")
		)
		(pad "2" smd circle
			(at -0.40005 0 270)
			(size 0 0)
			(layers "B.Cu" "B.Mask" "B.Paste")
			(net "PVDD18_S5_P1")
		)
	)
	(footprint ""
		(layer "B.Cu")
		(at 202.00112 -331.027786 -90)
		(property "Reference" "PC134"
			(at 0 0 90)
			(layer "B.SilkS")
			(hide yes)
			(effects
				(font
					(size 1.27 1.27)
				)
				(justify mirror)
			)
		)
		(property "Value" ""
			(at 0 0 90)
			(layer "B.Fab")
			(effects
				(font
					(size 1.27 1.27)
				)
				(justify mirror)
			)
		)
		(duplicate_pad_numbers_are_jumpers no)
		(fp_line
			(start -1.524 0.762)
			(end 1.524 0.762)
			(stroke
				(width 0.1524)
				(type default)
			)
			(layer "B.SilkS")
		)
		(fp_line
			(start 1.524 0.762)
			(end 1.524 -0.762)
			(stroke
				(width 0.1524)
				(type default)
			)
			(layer "B.SilkS")
		)
		(fp_line
			(start -1.524 -0.762)
			(end -1.524 0.762)
			(stroke
				(width 0.1524)
				(type default)
			)
			(layer "B.SilkS")
		)
		(fp_line
			(start 1.524 -0.762)
			(end -1.524 -0.762)
			(stroke
				(width 0.1524)
				(type default)
			)
			(layer "B.SilkS")
		)
		(fp_line
			(start -1.1049 0.724916)
			(end -1.1049 -0.724916)
			(stroke
				(width 0.1)
				(type default)
			)
			(layer "B.Fab")
		)
		(fp_line
			(start 1.1049 0.724916)
			(end -1.1049 0.724916)
			(stroke
				(width 0.1)
				(type default)
			)
			(layer "B.Fab")
		)
		(fp_line
			(start -1.1049 -0.724916)
			(end 1.1049 -0.724916)
			(stroke
				(width 0.1)
				(type default)
			)
			(layer "B.Fab")
		)
		(fp_line
			(start 1.1049 -0.724916)
			(end 1.1049 0.724916)
			(stroke
				(width 0.1)
				(type default)
			)
			(layer "B.Fab")
		)
		(pad "1" smd rect
			(at 0.889 0 270)
			(size 1.016 1.27)
			(layers "B.Cu" "B.Mask" "B.Paste")
			(net "PVDD_33_S5")
		)
		(pad "2" smd rect
			(at -0.889 0 270)
			(size 1.016 1.27)
			(layers "B.Cu" "B.Mask" "B.Paste")
			(net "GND")
		)
	)
	(footprint ""
		(layer "B.Cu")
		(at 373.329454 -258.830064)
		(property "Reference" "C2585"
			(at 0 0 0)
			(layer "B.SilkS")
			(hide yes)
			(effects
				(font
					(size 1.27 1.27)
				)
				(justify mirror)
			)
		)
		(property "Value" ""
			(at 0 0 0)
			(layer "B.Fab")
			(effects
				(font
					(size 1.27 1.27)
				)
				(justify mirror)
			)
		)
		(duplicate_pad_numbers_are_jumpers no)
		(fp_line
			(start -0.7874 -0.4064)
			(end -0.7874 0.4064)
			(stroke
				(width 0.1524)
				(type default)
			)
			(layer "B.SilkS")
		)
		(fp_line
			(start -0.7874 0.4064)
			(end 0.7874 0.4064)
			(stroke
				(width 0.1524)
				(type default)
			)
			(layer "B.SilkS")
		)
		(fp_line
			(start 0.7874 -0.4064)
			(end -0.7874 -0.4064)
			(stroke
				(width 0.1524)
				(type default)
			)
			(layer "B.SilkS")
		)
		(fp_line
			(start 0.7874 0.4064)
			(end 0.7874 -0.4064)
			(stroke
				(width 0.1524)
				(type default)
			)
			(layer "B.SilkS")
		)
		(fp_line
			(start -0.67945 -0.3048)
			(end -0.67945 0.3048)
			(stroke
				(width 0.1)
				(type default)
			)
			(layer "B.Fab")
		)
		(fp_line
			(start -0.67945 0.3048)
			(end -0.120396 0.3048)
			(stroke
				(width 0.1)
				(type default)
			)
			(layer "B.Fab")
		)
		(fp_line
			(start -0.12065 -0.3048)
			(end -0.67945 -0.3048)
			(stroke
				(width 0.1)
				(type default)
			)
			(layer "B.Fab")
		)
		(fp_line
			(start -0.12065 -0.2794)
			(end -0.12065 -0.3048)
			(stroke
				(width 0.1)
				(type default)
			)
			(layer "B.Fab")
		)
		(fp_line
			(start -0.120396 0.2794)
			(end 0.12065 0.2794)
			(stroke
				(width 0.1)
				(type default)
			)
			(layer "B.Fab")
		)
		(fp_line
			(start -0.120396 0.3048)
			(end -0.120396 0.2794)
			(stroke
				(width 0.1)
				(type default)
			)
			(layer "B.Fab")
		)
		(fp_line
			(start 0.12065 -0.305054)
			(end 0.12065 -0.2794)
			(stroke
				(width 0.1)
				(type default)
			)
			(layer "B.Fab")
		)
		(fp_line
			(start 0.12065 -0.2794)
			(end -0.12065 -0.2794)
			(stroke
				(width 0.1)
				(type default)
			)
			(layer "B.Fab")
		)
		(fp_line
			(start 0.12065 0.2794)
			(end 0.12065 0.3048)
			(stroke
				(width 0.1)
				(type default)
			)
			(layer "B.Fab")
		)
		(fp_line
			(start 0.12065 0.3048)
			(end 0.67945 0.3048)
			(stroke
				(width 0.1)
				(type default)
			)
			(layer "B.Fab")
		)
		(fp_line
			(start 0.67945 -0.305054)
			(end 0.12065 -0.305054)
			(stroke
				(width 0.1)
				(type default)
			)
			(layer "B.Fab")
		)
		(fp_line
			(start 0.67945 0.3048)
			(end 0.67945 -0.305054)
			(stroke
				(width 0.1)
				(type default)
			)
			(layer "B.Fab")
		)
		(pad "1" smd circle
			(at 0.40005 0 180)
			(size 0 0)
			(layers "B.Cu" "B.Mask" "B.Paste")
			(net "PVDDCR_SOC_P0")
		)
		(pad "2" smd circle
			(at -0.40005 0 180)
			(size 0 0)
			(layers "B.Cu" "B.Mask" "B.Paste")
			(net "GND")
		)
	)
	(footprint ""
		(layer "B.Cu")
		(at 165.006274 -386.766562 90)
		(property "Reference" "C382"
			(at 0 0 90)
			(layer "B.SilkS")
			(hide yes)
			(effects
				(font
					(size 1.27 1.27)
				)
				(justify mirror)
			)
		)
		(property "Value" ""
			(at 0 0 90)
			(layer "B.Fab")
			(effects
				(font
					(size 1.27 1.27)
				)
				(justify mirror)
			)
		)
		(duplicate_pad_numbers_are_jumpers no)
		(fp_line
			(start 0.299974 -0.150114)
			(end -0.299974 -0.150114)
			(stroke
				(width 0.1)
				(type default)
			)
			(layer "B.Fab")
		)
		(fp_line
			(start -0.299974 -0.150114)
			(end -0.299974 0.150114)
			(stroke
				(width 0.1)
				(type default)
			)
			(layer "B.Fab")
		)
		(fp_line
			(start 0.299974 0.150114)
			(end 0.299974 -0.150114)
			(stroke
				(width 0.1)
				(type default)
			)
			(layer "B.Fab")
		)
		(fp_line
			(start -0.299974 0.150114)
			(end 0.299974 0.150114)
			(stroke
				(width 0.1)
				(type default)
			)
			(layer "B.Fab")
		)
		(pad "1" smd rect
			(at 0.2667 0 270)
			(size 0.3048 0.381)
			(layers "B.Cu" "B.Mask" "B.Paste")
			(net "P0V9_CPU1_RT2_2A")
		)
		(pad "2" smd rect
			(at -0.2667 0 270)
			(size 0.3048 0.381)
			(layers "B.Cu" "B.Mask" "B.Paste")
			(net "GND")
		)
	)
	(footprint ""
		(layer "B.Cu")
		(at 130.104642 -72.39254)
		(property "Reference" "PC6026"
			(at 0 0 0)
			(layer "B.SilkS")
			(hide yes)
			(effects
				(font
					(size 1.27 1.27)
				)
				(justify mirror)
			)
		)
		(property "Value" ""
			(at 0 0 0)
			(layer "B.Fab")
			(effects
				(font
					(size 1.27 1.27)
				)
				(justify mirror)
			)
		)
		(duplicate_pad_numbers_are_jumpers no)
		(fp_line
			(start -1.524 -0.762)
			(end -1.524 0.762)
			(stroke
				(width 0.1524)
				(type default)
			)
			(layer "B.SilkS")
		)
		(fp_line
			(start -1.524 0.762)
			(end 1.524 0.762)
			(stroke
				(width 0.1524)
				(type default)
			)
			(layer "B.SilkS")
		)
		(fp_line
			(start 1.524 -0.762)
			(end -1.524 -0.762)
			(stroke
				(width 0.1524)
				(type default)
			)
			(layer "B.SilkS")
		)
		(fp_line
			(start 1.524 0.762)
			(end 1.524 -0.762)
			(stroke
				(width 0.1524)
				(type default)
			)
			(layer "B.SilkS")
		)
		(fp_line
			(start -1.1049 -0.724916)
			(end 1.1049 -0.724916)
			(stroke
				(width 0.1)
				(type default)
			)
			(layer "B.Fab")
		)
		(fp_line
			(start -1.1049 0.724916)
			(end -1.1049 -0.724916)
			(stroke
				(width 0.1)
				(type default)
			)
			(layer "B.Fab")
		)
		(fp_line
			(start 1.1049 -0.724916)
			(end 1.1049 0.724916)
			(stroke
				(width 0.1)
				(type default)
			)
			(layer "B.Fab")
		)
		(fp_line
			(start 1.1049 0.724916)
			(end -1.1049 0.724916)
			(stroke
				(width 0.1)
				(type default)
			)
			(layer "B.Fab")
		)
		(pad "1" smd rect
			(at 0.889 0)
			(size 1.016 1.27)
			(layers "B.Cu" "B.Mask" "B.Paste")
			(net "P1V2_AUX")
		)
		(pad "2" smd rect
			(at -0.889 0)
			(size 1.016 1.27)
			(layers "B.Cu" "B.Mask" "B.Paste")
			(net "GND")
		)
	)
	(footprint ""
		(layer "B.Cu")
		(at 13.018262 -389.526526 -90)
		(property "Reference" "PR6621"
			(at 0 0 90)
			(layer "B.SilkS")
			(hide yes)
			(effects
				(font
					(size 1.27 1.27)
				)
				(justify mirror)
			)
		)
		(property "Value" ""
			(at 0 0 90)
			(layer "B.Fab")
			(effects
				(font
					(size 1.27 1.27)
				)
				(justify mirror)
			)
		)
		(duplicate_pad_numbers_are_jumpers no)
		(fp_line
			(start -0.7874 0.4064)
			(end 0.7874 0.4064)
			(stroke
				(width 0.1524)
				(type default)
			)
			(layer "B.SilkS")
		)
		(fp_line
			(start 0.7874 0.4064)
			(end 0.7874 -0.4064)
			(stroke
				(width 0.1524)
				(type default)
			)
			(layer "B.SilkS")
		)
		(fp_line
			(start -0.7874 -0.4064)
			(end -0.7874 0.4064)
			(stroke
				(width 0.1524)
				(type default)
			)
			(layer "B.SilkS")
		)
		(fp_line
			(start 0.7874 -0.4064)
			(end -0.7874 -0.4064)
			(stroke
				(width 0.1524)
				(type default)
			)
			(layer "B.SilkS")
		)
		(fp_line
			(start -0.67945 0.3048)
			(end -0.120396 0.3048)
			(stroke
				(width 0.1)
				(type default)
			)
			(layer "B.Fab")
		)
		(fp_line
			(start -0.120396 0.3048)
			(end -0.120396 0.2794)
			(stroke
				(width 0.1)
				(type default)
			)
			(layer "B.Fab")
		)
		(fp_line
			(start 0.12065 0.3048)
			(end 0.67945 0.3048)
			(stroke
				(width 0.1)
				(type default)
			)
			(layer "B.Fab")
		)
		(fp_line
			(start 0.67945 0.3048)
			(end 0.67945 -0.305054)
			(stroke
				(width 0.1)
				(type default)
			)
			(layer "B.Fab")
		)
		(fp_line
			(start -0.120396 0.2794)
			(end 0.12065 0.2794)
			(stroke
				(width 0.1)
				(type default)
			)
			(layer "B.Fab")
		)
		(fp_line
			(start 0.12065 0.2794)
			(end 0.12065 0.3048)
			(stroke
				(width 0.1)
				(type default)
			)
			(layer "B.Fab")
		)
		(fp_line
			(start -0.12065 -0.2794)
			(end -0.12065 -0.3048)
			(stroke
				(width 0.1)
				(type default)
			)
			(layer "B.Fab")
		)
		(fp_line
			(start 0.12065 -0.2794)
			(end -0.12065 -0.2794)
			(stroke
				(width 0.1)
				(type default)
			)
			(layer "B.Fab")
		)
		(fp_line
			(start -0.67945 -0.3048)
			(end -0.67945 0.3048)
			(stroke
				(width 0.1)
				(type default)
			)
			(layer "B.Fab")
		)
		(fp_line
			(start -0.12065 -0.3048)
			(end -0.67945 -0.3048)
			(stroke
				(width 0.1)
				(type default)
			)
			(layer "B.Fab")
		)
		(fp_line
			(start 0.12065 -0.305054)
			(end 0.12065 -0.2794)
			(stroke
				(width 0.1)
				(type default)
			)
			(layer "B.Fab")
		)
		(fp_line
			(start 0.67945 -0.305054)
			(end 0.12065 -0.305054)
			(stroke
				(width 0.1)
				(type default)
			)
			(layer "B.Fab")
		)
		(pad "1" smd circle
			(at 0.40005 0 90)
			(size 0 0)
			(layers "B.Cu" "B.Mask" "B.Paste")
			(net "P0V9_RETIMER_CPU1_PVCC")
		)
		(pad "2" smd circle
			(at -0.40005 0 90)
			(size 0 0)
			(layers "B.Cu" "B.Mask" "B.Paste")
			(net "P0V9_RETIMER_CPU1_VCC1")
		)
	)
	(footprint ""
		(layer "B.Cu")
		(at 136.93648 -9.032748 -90)
		(property "Reference" "R3777"
			(at 0 0 90)
			(layer "B.SilkS")
			(hide yes)
			(effects
				(font
					(size 1.27 1.27)
				)
				(justify mirror)
			)
		)
		(property "Value" ""
			(at 0 0 90)
			(layer "B.Fab")
			(effects
				(font
					(size 1.27 1.27)
				)
				(justify mirror)
			)
		)
		(duplicate_pad_numbers_are_jumpers no)
		(fp_line
			(start -0.7874 0.4064)
			(end 0.7874 0.4064)
			(stroke
				(width 0.1524)
				(type default)
			)
			(layer "B.SilkS")
		)
		(fp_line
			(start 0.7874 0.4064)
			(end 0.7874 -0.4064)
			(stroke
				(width 0.1524)
				(type default)
			)
			(layer "B.SilkS")
		)
		(fp_line
			(start -0.7874 -0.4064)
			(end -0.7874 0.4064)
			(stroke
				(width 0.1524)
				(type default)
			)
			(layer "B.SilkS")
		)
		(fp_line
			(start 0.7874 -0.4064)
			(end -0.7874 -0.4064)
			(stroke
				(width 0.1524)
				(type default)
			)
			(layer "B.SilkS")
		)
		(fp_line
			(start -0.67945 0.3048)
			(end -0.120396 0.3048)
			(stroke
				(width 0.1)
				(type default)
			)
			(layer "B.Fab")
		)
		(fp_line
			(start -0.120396 0.3048)
			(end -0.120396 0.2794)
			(stroke
				(width 0.1)
				(type default)
			)
			(layer "B.Fab")
		)
		(fp_line
			(start 0.12065 0.3048)
			(end 0.67945 0.3048)
			(stroke
				(width 0.1)
				(type default)
			)
			(layer "B.Fab")
		)
		(fp_line
			(start 0.67945 0.3048)
			(end 0.67945 -0.305054)
			(stroke
				(width 0.1)
				(type default)
			)
			(layer "B.Fab")
		)
		(fp_line
			(start -0.120396 0.2794)
			(end 0.12065 0.2794)
			(stroke
				(width 0.1)
				(type default)
			)
			(layer "B.Fab")
		)
		(fp_line
			(start 0.12065 0.2794)
			(end 0.12065 0.3048)
			(stroke
				(width 0.1)
				(type default)
			)
			(layer "B.Fab")
		)
		(fp_line
			(start -0.12065 -0.2794)
			(end -0.12065 -0.3048)
			(stroke
				(width 0.1)
				(type default)
			)
			(layer "B.Fab")
		)
		(fp_line
			(start 0.12065 -0.2794)
			(end -0.12065 -0.2794)
			(stroke
				(width 0.1)
				(type default)
			)
			(layer "B.Fab")
		)
		(fp_line
			(start -0.67945 -0.3048)
			(end -0.67945 0.3048)
			(stroke
				(width 0.1)
				(type default)
			)
			(layer "B.Fab")
		)
		(fp_line
			(start -0.12065 -0.3048)
			(end -0.67945 -0.3048)
			(stroke
				(width 0.1)
				(type default)
			)
			(layer "B.Fab")
		)
		(fp_line
			(start 0.12065 -0.305054)
			(end 0.12065 -0.2794)
			(stroke
				(width 0.1)
				(type default)
			)
			(layer "B.Fab")
		)
		(fp_line
			(start 0.67945 -0.305054)
			(end 0.12065 -0.305054)
			(stroke
				(width 0.1)
				(type default)
			)
			(layer "B.Fab")
		)
		(pad "1" smd circle
			(at 0.40005 0 90)
			(size 0 0)
			(layers "B.Cu" "B.Mask" "B.Paste")
			(net "FM_UARTSW_LSB_N")
		)
		(pad "2" smd circle
			(at -0.40005 0 90)
			(size 0 0)
			(layers "B.Cu" "B.Mask" "B.Paste")
			(net "FM_UARTSW_LSB_R")
		)
	)
)
